(kicad_pcb
	(version 20260206)
	(generator "pcbnew")
	(generator_version "10.0")
	(general
		(thickness 1.6)
		(legacy_teardrops no)
	)
	(paper "A4")
	(title_block
		(title "12092022_DA0F0TMDCD0_F0T_Management_Board_D_brd_V3_OCP.brd")
		(comment 1 "Grand Teton / footprints 401-406 of 1440")
	)
	(layers
		(0 "F.Cu" signal "TOP")
		(4 "In1.Cu" signal "GND")
		(6 "In2.Cu" signal "IN1")
		(8 "In3.Cu" signal "GND1")
		(10 "In4.Cu" signal "IN2")
		(12 "In5.Cu" signal "VCC")
		(14 "In6.Cu" signal "VCC1")
		(16 "In7.Cu" signal "IN3")
		(18 "In8.Cu" signal "GND2")
		(20 "In9.Cu" signal "IN4")
		(22 "In10.Cu" signal "GND3")
		(2 "B.Cu" signal "BOTTOM")
		(9 "F.Adhes" user "F.Adhesive")
		(11 "B.Adhes" user "B.Adhesive")
		(13 "F.Paste" user "Package Geometry/Pastemask Top")
		(15 "B.Paste" user "Package Geometry/Pastemask Bottom")
		(5 "F.SilkS" user "Ref Des/Silkscreen Top")
		(7 "B.SilkS" user "Ref Des/Silkscreen Bottom")
		(1 "F.Mask" user "Board Geometry/Soldermask Top")
		(3 "B.Mask" user "Board Geometry/Soldermask Bottom")
		(17 "Dwgs.User" user "User.Drawings")
		(19 "Cmts.User" user "User.Comments")
		(21 "Eco1.User" user "User.Eco1")
		(23 "Eco2.User" user "User.Eco2")
		(25 "Edge.Cuts" user "Board Geometry/Outline")
		(27 "Margin" user)
		(31 "F.CrtYd" user "Package Geometry/Place Bound Top")
		(29 "B.CrtYd" user "Package Geometry/Place Bound Bottom")
		(35 "F.Fab" user "Ref Des/Assembly Top")
		(33 "B.Fab" user "Ref Des/Assembly Bottom")
	)
	(footprint ""
		(layer "F.Cu")
		(at 64.9732 -24.1554 180)
		(property "Reference" "R511"
			(at 0 0 180)
			(layer "F.SilkS")
			(hide yes)
			(effects
				(font
					(size 1.27 1.27)
				)
			)
		)
		(property "Value" ""
			(at 0 0 180)
			(layer "F.Fab")
			(effects
				(font
					(size 1.27 1.27)
				)
			)
		)
		(duplicate_pad_numbers_are_jumpers no)
		(fp_line
			(start 0.7874 0.4064)
			(end -0.7874 0.4064)
			(stroke
				(width 0.1524)
				(type default)
			)
			(layer "F.SilkS")
		)
		(fp_line
			(start 0.7874 -0.4064)
			(end 0.7874 0.4064)
			(stroke
				(width 0.1524)
				(type default)
			)
			(layer "F.SilkS")
		)
		(fp_line
			(start -0.7874 0.4064)
			(end -0.7874 -0.4064)
			(stroke
				(width 0.1524)
				(type default)
			)
			(layer "F.SilkS")
		)
		(fp_line
			(start -0.7874 -0.4064)
			(end 0.7874 -0.4064)
			(stroke
				(width 0.1524)
				(type default)
			)
			(layer "F.SilkS")
		)
		(fp_line
			(start 0.67945 0.3048)
			(end 0.120396 0.3048)
			(stroke
				(width 0.1)
				(type default)
			)
			(layer "F.Fab")
		)
		(fp_line
			(start 0.67945 -0.3048)
			(end 0.67945 0.3048)
			(stroke
				(width 0.1)
				(type default)
			)
			(layer "F.Fab")
		)
		(fp_line
			(start 0.12065 -0.2794)
			(end 0.12065 -0.3048)
			(stroke
				(width 0.1)
				(type default)
			)
			(layer "F.Fab")
		)
		(fp_line
			(start 0.12065 -0.3048)
			(end 0.67945 -0.3048)
			(stroke
				(width 0.1)
				(type default)
			)
			(layer "F.Fab")
		)
		(fp_line
			(start 0.120396 0.3048)
			(end 0.120396 0.2794)
			(stroke
				(width 0.1)
				(type default)
			)
			(layer "F.Fab")
		)
		(fp_line
			(start 0.120396 0.2794)
			(end -0.12065 0.2794)
			(stroke
				(width 0.1)
				(type default)
			)
			(layer "F.Fab")
		)
		(fp_line
			(start -0.12065 0.3048)
			(end -0.67945 0.3048)
			(stroke
				(width 0.1)
				(type default)
			)
			(layer "F.Fab")
		)
		(fp_line
			(start -0.12065 0.2794)
			(end -0.12065 0.3048)
			(stroke
				(width 0.1)
				(type default)
			)
			(layer "F.Fab")
		)
		(fp_line
			(start -0.12065 -0.2794)
			(end 0.12065 -0.2794)
			(stroke
				(width 0.1)
				(type default)
			)
			(layer "F.Fab")
		)
		(fp_line
			(start -0.12065 -0.305054)
			(end -0.12065 -0.2794)
			(stroke
				(width 0.1)
				(type default)
			)
			(layer "F.Fab")
		)
		(fp_line
			(start -0.67945 0.3048)
			(end -0.67945 -0.305054)
			(stroke
				(width 0.1)
				(type default)
			)
			(layer "F.Fab")
		)
		(fp_line
			(start -0.67945 -0.305054)
			(end -0.12065 -0.305054)
			(stroke
				(width 0.1)
				(type default)
			)
			(layer "F.Fab")
		)
		(pad "1" smd circle
			(at -0.40005 0 180)
			(size 0 0)
			(layers "F.Cu" "F.Mask" "F.Paste")
			(net "JTAG_SCM_TMS")
		)
		(pad "2" smd circle
			(at 0.40005 0 180)
			(size 0 0)
			(layers "F.Cu" "F.Mask" "F.Paste")
			(net "JTAG_SCM_PLD_TMS")
		)
	)
	(footprint ""
		(layer "F.Cu")
		(at 17.4752 -83.7692 -90)
		(property "Reference" "R447"
			(at 0 0 270)
			(layer "F.SilkS")
			(hide yes)
			(effects
				(font
					(size 1.27 1.27)
				)
			)
		)
		(property "Value" ""
			(at 0 0 270)
			(layer "F.Fab")
			(effects
				(font
					(size 1.27 1.27)
				)
			)
		)
		(duplicate_pad_numbers_are_jumpers no)
		(fp_line
			(start -0.7874 0.4064)
			(end -0.7874 -0.4064)
			(stroke
				(width 0.1524)
				(type default)
			)
			(layer "F.SilkS")
		)
		(fp_line
			(start 0.7874 0.4064)
			(end -0.7874 0.4064)
			(stroke
				(width 0.1524)
				(type default)
			)
			(layer "F.SilkS")
		)
		(fp_line
			(start -0.7874 -0.4064)
			(end 0.7874 -0.4064)
			(stroke
				(width 0.1524)
				(type default)
			)
			(layer "F.SilkS")
		)
		(fp_line
			(start 0.7874 -0.4064)
			(end 0.7874 0.4064)
			(stroke
				(width 0.1524)
				(type default)
			)
			(layer "F.SilkS")
		)
		(fp_line
			(start -0.67945 0.3048)
			(end -0.67945 -0.305054)
			(stroke
				(width 0.1)
				(type default)
			)
			(layer "F.Fab")
		)
		(fp_line
			(start -0.12065 0.3048)
			(end -0.67945 0.3048)
			(stroke
				(width 0.1)
				(type default)
			)
			(layer "F.Fab")
		)
		(fp_line
			(start 0.120396 0.3048)
			(end 0.120396 0.2794)
			(stroke
				(width 0.1)
				(type default)
			)
			(layer "F.Fab")
		)
		(fp_line
			(start 0.67945 0.3048)
			(end 0.120396 0.3048)
			(stroke
				(width 0.1)
				(type default)
			)
			(layer "F.Fab")
		)
		(fp_line
			(start -0.12065 0.2794)
			(end -0.12065 0.3048)
			(stroke
				(width 0.1)
				(type default)
			)
			(layer "F.Fab")
		)
		(fp_line
			(start 0.120396 0.2794)
			(end -0.12065 0.2794)
			(stroke
				(width 0.1)
				(type default)
			)
			(layer "F.Fab")
		)
		(fp_line
			(start -0.12065 -0.2794)
			(end 0.12065 -0.2794)
			(stroke
				(width 0.1)
				(type default)
			)
			(layer "F.Fab")
		)
		(fp_line
			(start 0.12065 -0.2794)
			(end 0.12065 -0.3048)
			(stroke
				(width 0.1)
				(type default)
			)
			(layer "F.Fab")
		)
		(fp_line
			(start 0.12065 -0.3048)
			(end 0.67945 -0.3048)
			(stroke
				(width 0.1)
				(type default)
			)
			(layer "F.Fab")
		)
		(fp_line
			(start 0.67945 -0.3048)
			(end 0.67945 0.3048)
			(stroke
				(width 0.1)
				(type default)
			)
			(layer "F.Fab")
		)
		(fp_line
			(start -0.67945 -0.305054)
			(end -0.12065 -0.305054)
			(stroke
				(width 0.1)
				(type default)
			)
			(layer "F.Fab")
		)
		(fp_line
			(start -0.12065 -0.305054)
			(end -0.12065 -0.2794)
			(stroke
				(width 0.1)
				(type default)
			)
			(layer "F.Fab")
		)
		(pad "1" smd circle
			(at -0.40005 0 270)
			(size 0 0)
			(layers "F.Cu" "F.Mask" "F.Paste")
			(net "RST_EXTRST_R_N")
		)
		(pad "2" smd circle
			(at 0.40005 0 270)
			(size 0 0)
			(layers "F.Cu" "F.Mask" "F.Paste")
			(net "RST_EXTRST_N")
		)
	)
	(footprint ""
		(layer "F.Cu")
		(at 31.56204 -68.504054 90)
		(property "Reference" "R652"
			(at 0 0 90)
			(layer "F.SilkS")
			(hide yes)
			(effects
				(font
					(size 1.27 1.27)
				)
			)
		)
		(property "Value" ""
			(at 0 0 90)
			(layer "F.Fab")
			(effects
				(font
					(size 1.27 1.27)
				)
			)
		)
		(duplicate_pad_numbers_are_jumpers no)
		(fp_line
			(start 0.7874 -0.4064)
			(end 0.7874 0.4064)
			(stroke
				(width 0.1524)
				(type default)
			)
			(layer "F.SilkS")
		)
		(fp_line
			(start -0.7874 -0.4064)
			(end 0.7874 -0.4064)
			(stroke
				(width 0.1524)
				(type default)
			)
			(layer "F.SilkS")
		)
		(fp_line
			(start 0.7874 0.4064)
			(end -0.7874 0.4064)
			(stroke
				(width 0.1524)
				(type default)
			)
			(layer "F.SilkS")
		)
		(fp_line
			(start -0.7874 0.4064)
			(end -0.7874 -0.4064)
			(stroke
				(width 0.1524)
				(type default)
			)
			(layer "F.SilkS")
		)
		(fp_line
			(start -0.12065 -0.305054)
			(end -0.12065 -0.2794)
			(stroke
				(width 0.1)
				(type default)
			)
			(layer "F.Fab")
		)
		(fp_line
			(start -0.67945 -0.305054)
			(end -0.12065 -0.305054)
			(stroke
				(width 0.1)
				(type default)
			)
			(layer "F.Fab")
		)
		(fp_line
			(start 0.67945 -0.3048)
			(end 0.67945 0.3048)
			(stroke
				(width 0.1)
				(type default)
			)
			(layer "F.Fab")
		)
		(fp_line
			(start 0.12065 -0.3048)
			(end 0.67945 -0.3048)
			(stroke
				(width 0.1)
				(type default)
			)
			(layer "F.Fab")
		)
		(fp_line
			(start 0.12065 -0.2794)
			(end 0.12065 -0.3048)
			(stroke
				(width 0.1)
				(type default)
			)
			(layer "F.Fab")
		)
		(fp_line
			(start -0.12065 -0.2794)
			(end 0.12065 -0.2794)
			(stroke
				(width 0.1)
				(type default)
			)
			(layer "F.Fab")
		)
		(fp_line
			(start 0.120396 0.2794)
			(end -0.12065 0.2794)
			(stroke
				(width 0.1)
				(type default)
			)
			(layer "F.Fab")
		)
		(fp_line
			(start -0.12065 0.2794)
			(end -0.12065 0.3048)
			(stroke
				(width 0.1)
				(type default)
			)
			(layer "F.Fab")
		)
		(fp_line
			(start 0.67945 0.3048)
			(end 0.120396 0.3048)
			(stroke
				(width 0.1)
				(type default)
			)
			(layer "F.Fab")
		)
		(fp_line
			(start 0.120396 0.3048)
			(end 0.120396 0.2794)
			(stroke
				(width 0.1)
				(type default)
			)
			(layer "F.Fab")
		)
		(fp_line
			(start -0.12065 0.3048)
			(end -0.67945 0.3048)
			(stroke
				(width 0.1)
				(type default)
			)
			(layer "F.Fab")
		)
		(fp_line
			(start -0.67945 0.3048)
			(end -0.67945 -0.305054)
			(stroke
				(width 0.1)
				(type default)
			)
			(layer "F.Fab")
		)
		(pad "1" smd circle
			(at -0.40005 0 90)
			(size 0 0)
			(layers "F.Cu" "F.Mask" "F.Paste")
			(net "BMC_EMMC_DT5")
		)
		(pad "2" smd circle
			(at 0.40005 0 90)
			(size 0 0)
			(layers "F.Cu" "F.Mask" "F.Paste")
			(net "EMMC_DT5_R")
		)
	)
	(footprint ""
		(layer "F.Cu")
		(at 28.270454 -17.008602)
		(property "Reference" "R385"
			(at 0 0 0)
			(layer "F.SilkS")
			(hide yes)
			(effects
				(font
					(size 1.27 1.27)
				)
			)
		)
		(property "Value" ""
			(at 0 0 0)
			(layer "F.Fab")
			(effects
				(font
					(size 1.27 1.27)
				)
			)
		)
		(duplicate_pad_numbers_are_jumpers no)
		(fp_line
			(start -0.7874 -0.4064)
			(end 0.7874 -0.4064)
			(stroke
				(width 0.1524)
				(type default)
			)
			(layer "F.SilkS")
		)
		(fp_line
			(start 0.7874 0.4064)
			(end -0.7874 0.4064)
			(stroke
				(width 0.1524)
				(type default)
			)
			(layer "F.SilkS")
		)
		(fp_line
			(start -0.67945 -0.305054)
			(end -0.12065 -0.305054)
			(stroke
				(width 0.1)
				(type default)
			)
			(layer "F.Fab")
		)
		(fp_line
			(start -0.67945 0.3048)
			(end -0.67945 -0.305054)
			(stroke
				(width 0.1)
				(type default)
			)
			(layer "F.Fab")
		)
		(fp_line
			(start -0.12065 -0.305054)
			(end -0.12065 -0.2794)
			(stroke
				(width 0.1)
				(type default)
			)
			(layer "F.Fab")
		)
		(fp_line
			(start -0.12065 -0.2794)
			(end 0.12065 -0.2794)
			(stroke
				(width 0.1)
				(type default)
			)
			(layer "F.Fab")
		)
		(fp_line
			(start -0.12065 0.2794)
			(end -0.12065 0.3048)
			(stroke
				(width 0.1)
				(type default)
			)
			(layer "F.Fab")
		)
		(fp_line
			(start -0.12065 0.3048)
			(end -0.67945 0.3048)
			(stroke
				(width 0.1)
				(type default)
			)
			(layer "F.Fab")
		)
		(fp_line
			(start 0.120396 0.2794)
			(end -0.12065 0.2794)
			(stroke
				(width 0.1)
				(type default)
			)
			(layer "F.Fab")
		)
		(fp_line
			(start 0.120396 0.3048)
			(end 0.120396 0.2794)
			(stroke
				(width 0.1)
				(type default)
			)
			(layer "F.Fab")
		)
		(fp_line
			(start 0.12065 -0.3048)
			(end 0.67945 -0.3048)
			(stroke
				(width 0.1)
				(type default)
			)
			(layer "F.Fab")
		)
		(fp_line
			(start 0.12065 -0.2794)
			(end 0.12065 -0.3048)
			(stroke
				(width 0.1)
				(type default)
			)
			(layer "F.Fab")
		)
		(fp_line
			(start 0.67945 -0.3048)
			(end 0.67945 0.3048)
			(stroke
				(width 0.1)
				(type default)
			)
			(layer "F.Fab")
		)
		(fp_line
			(start 0.67945 0.3048)
			(end 0.120396 0.3048)
			(stroke
				(width 0.1)
				(type default)
			)
			(layer "F.Fab")
		)
		(pad "1" smd circle
			(at -0.40005 0)
			(size 0 0)
			(layers "F.Cu" "F.Mask" "F.Paste")
			(net "USB_FPNL_DN")
		)
		(pad "2" smd circle
			(at 0.40005 0)
			(size 0 0)
			(layers "F.Cu" "F.Mask" "F.Paste")
			(net "USB2_01_F_DN")
		)
	)
	(footprint ""
		(layer "F.Cu")
		(at 79.739744 -37.559488 -90)
		(property "Reference" "R373"
			(at 0 0 270)
			(layer "F.SilkS")
			(hide yes)
			(effects
				(font
					(size 1.27 1.27)
				)
			)
		)
		(property "Value" ""
			(at 0 0 270)
			(layer "F.Fab")
			(effects
				(font
					(size 1.27 1.27)
				)
			)
		)
		(duplicate_pad_numbers_are_jumpers no)
		(fp_line
			(start -0.7874 0.4064)
			(end -0.7874 -0.4064)
			(stroke
				(width 0.1524)
				(type default)
			)
			(layer "F.SilkS")
		)
		(fp_line
			(start 0.7874 0.4064)
			(end -0.7874 0.4064)
			(stroke
				(width 0.1524)
				(type default)
			)
			(layer "F.SilkS")
		)
		(fp_line
			(start -0.7874 -0.4064)
			(end 0.7874 -0.4064)
			(stroke
				(width 0.1524)
				(type default)
			)
			(layer "F.SilkS")
		)
		(fp_line
			(start 0.7874 -0.4064)
			(end 0.7874 0.4064)
			(stroke
				(width 0.1524)
				(type default)
			)
			(layer "F.SilkS")
		)
		(fp_line
			(start -0.67945 0.3048)
			(end -0.67945 -0.305054)
			(stroke
				(width 0.1)
				(type default)
			)
			(layer "F.Fab")
		)
		(fp_line
			(start -0.12065 0.3048)
			(end -0.67945 0.3048)
			(stroke
				(width 0.1)
				(type default)
			)
			(layer "F.Fab")
		)
		(fp_line
			(start 0.120396 0.3048)
			(end 0.120396 0.2794)
			(stroke
				(width 0.1)
				(type default)
			)
			(layer "F.Fab")
		)
		(fp_line
			(start 0.67945 0.3048)
			(end 0.120396 0.3048)
			(stroke
				(width 0.1)
				(type default)
			)
			(layer "F.Fab")
		)
		(fp_line
			(start -0.12065 0.2794)
			(end -0.12065 0.3048)
			(stroke
				(width 0.1)
				(type default)
			)
			(layer "F.Fab")
		)
		(fp_line
			(start 0.120396 0.2794)
			(end -0.12065 0.2794)
			(stroke
				(width 0.1)
				(type default)
			)
			(layer "F.Fab")
		)
		(fp_line
			(start -0.12065 -0.2794)
			(end 0.12065 -0.2794)
			(stroke
				(width 0.1)
				(type default)
			)
			(layer "F.Fab")
		)
		(fp_line
			(start 0.12065 -0.2794)
			(end 0.12065 -0.3048)
			(stroke
				(width 0.1)
				(type default)
			)
			(layer "F.Fab")
		)
		(fp_line
			(start 0.12065 -0.3048)
			(end 0.67945 -0.3048)
			(stroke
				(width 0.1)
				(type default)
			)
			(layer "F.Fab")
		)
		(fp_line
			(start 0.67945 -0.3048)
			(end 0.67945 0.3048)
			(stroke
				(width 0.1)
				(type default)
			)
			(layer "F.Fab")
		)
		(fp_line
			(start -0.67945 -0.305054)
			(end -0.12065 -0.305054)
			(stroke
				(width 0.1)
				(type default)
			)
			(layer "F.Fab")
		)
		(fp_line
			(start -0.12065 -0.305054)
			(end -0.12065 -0.2794)
			(stroke
				(width 0.1)
				(type default)
			)
			(layer "F.Fab")
		)
		(pad "1" smd circle
			(at -0.40005 0 270)
			(size 0 0)
			(layers "F.Cu" "F.Mask" "F.Paste")
			(net "M_BMC_DDR4_MODT")
		)
		(pad "2" smd circle
			(at 0.40005 0 270)
			(size 0 0)
			(layers "F.Cu" "F.Mask" "F.Paste")
			(net "P1V2_AUX")
		)
	)
	(footprint ""
		(layer "F.Cu")
		(at 40.222678 -53.992272)
		(property "Reference" "C294"
			(at 0 0 0)
			(layer "F.SilkS")
			(hide yes)
			(effects
				(font
					(size 1.27 1.27)
				)
			)
		)
		(property "Value" ""
			(at 0 0 0)
			(layer "F.Fab")
			(effects
				(font
					(size 1.27 1.27)
				)
			)
		)
		(duplicate_pad_numbers_are_jumpers no)
		(fp_line
			(start -0.7874 -0.4064)
			(end 0.7874 -0.4064)
			(stroke
				(width 0.1524)
				(type default)
			)
			(layer "F.SilkS")
		)
		(fp_line
			(start -0.7874 0.4064)
			(end -0.7874 -0.4064)
			(stroke
				(width 0.1524)
				(type default)
			)
			(layer "F.SilkS")
		)
		(fp_line
			(start 0.7874 -0.4064)
			(end 0.7874 0.4064)
			(stroke
				(width 0.1524)
				(type default)
			)
			(layer "F.SilkS")
		)
		(fp_line
			(start 0.7874 0.4064)
			(end -0.7874 0.4064)
			(stroke
				(width 0.1524)
				(type default)
			)
			(layer "F.SilkS")
		)
		(fp_line
			(start -0.67945 -0.305054)
			(end -0.12065 -0.305054)
			(stroke
				(width 0.1)
				(type default)
			)
			(layer "F.Fab")
		)
		(fp_line
			(start -0.67945 0.3048)
			(end -0.67945 -0.305054)
			(stroke
				(width 0.1)
				(type default)
			)
			(layer "F.Fab")
		)
		(fp_line
			(start -0.12065 -0.305054)
			(end -0.12065 -0.2794)
			(stroke
				(width 0.1)
				(type default)
			)
			(layer "F.Fab")
		)
		(fp_line
			(start -0.12065 -0.2794)
			(end 0.12065 -0.2794)
			(stroke
				(width 0.1)
				(type default)
			)
			(layer "F.Fab")
		)
		(fp_line
			(start -0.12065 0.2794)
			(end -0.12065 0.3048)
			(stroke
				(width 0.1)
				(type default)
			)
			(layer "F.Fab")
		)
		(fp_line
			(start -0.12065 0.3048)
			(end -0.67945 0.3048)
			(stroke
				(width 0.1)
				(type default)
			)
			(layer "F.Fab")
		)
		(fp_line
			(start 0.120396 0.2794)
			(end -0.12065 0.2794)
			(stroke
				(width 0.1)
				(type default)
			)
			(layer "F.Fab")
		)
		(fp_line
			(start 0.120396 0.3048)
			(end 0.120396 0.2794)
			(stroke
				(width 0.1)
				(type default)
			)
			(layer "F.Fab")
		)
		(fp_line
			(start 0.12065 -0.3048)
			(end 0.67945 -0.3048)
			(stroke
				(width 0.1)
				(type default)
			)
			(layer "F.Fab")
		)
		(fp_line
			(start 0.12065 -0.2794)
			(end 0.12065 -0.3048)
			(stroke
				(width 0.1)
				(type default)
			)
			(layer "F.Fab")
		)
		(fp_line
			(start 0.67945 -0.3048)
			(end 0.67945 0.3048)
			(stroke
				(width 0.1)
				(type default)
			)
			(layer "F.Fab")
		)
		(fp_line
			(start 0.67945 0.3048)
			(end 0.120396 0.3048)
			(stroke
				(width 0.1)
				(type default)
			)
			(layer "F.Fab")
		)
		(pad "1" smd circle
			(at -0.40005 0)
			(size 0 0)
			(layers "F.Cu" "F.Mask" "F.Paste")
			(net "P1V8_AUX")
		)
		(pad "2" smd circle
			(at 0.40005 0)
			(size 0 0)
			(layers "F.Cu" "F.Mask" "F.Paste")
			(net "GND")
		)
	)
)
